(kicad_pcb
	(version 20260206)
	(generator "pcbnew")
	(generator_version "10.0")
	(general
		(thickness 1.6)
		(legacy_teardrops no)
	)
	(paper "A4")
	(title_block
		(title "peb — Lightning_PEB_BRD.brd")
		(comment 1 "Lightning (Wiwynn / Facebook NVMe JBOF) / footprint 1445 of 2563 (U1), pads 235-353 of 1311")
	)
	(layers
		(0 "F.Cu" signal "TOP")
		(4 "In1.Cu" signal "L2GND")
		(6 "In2.Cu" signal "L3")
		(8 "In3.Cu" signal "L4VCC")
		(10 "In4.Cu" signal "L5VCC")
		(12 "In5.Cu" signal "L6")
		(14 "In6.Cu" signal "L7GND")
		(2 "B.Cu" signal "BOTTOM")
		(9 "F.Adhes" user "F.Adhesive")
		(11 "B.Adhes" user "B.Adhesive")
		(13 "F.Paste" user "Package Geometry/Pastemask Top")
		(15 "B.Paste" user "Package Geometry/Pastemask Bottom")
		(5 "F.SilkS" user "Ref Des/Silkscreen Top")
		(7 "B.SilkS" user "Ref Des/Silkscreen Bottom")
		(1 "F.Mask" user "Board Geometry/Soldermask Top")
		(3 "B.Mask" user "Board Geometry/Soldermask Bottom")
		(17 "Dwgs.User" user "User.Drawings")
		(19 "Cmts.User" user "User.Comments")
		(21 "Eco1.User" user "User.Eco1")
		(23 "Eco2.User" user "User.Eco2")
		(25 "Edge.Cuts" user "Board Geometry/Outline")
		(27 "Margin" user)
		(31 "F.CrtYd" user "Package Geometry/Place Bound Top")
		(29 "B.CrtYd" user "Package Geometry/Place Bound Bottom")
		(35 "F.Fab" user "Ref Des/Assembly Top")
		(33 "B.Fab" user "Ref Des/Assembly Bottom")
	)
	(footprint ""
		(layer "F.Cu")
		(at 240.599976 -47.999904 -90)
		(property "Reference" "U1"
			(at 0 0 270)
			(layer "F.SilkS")
			(hide yes)
			(effects
				(font
					(size 1.27 1.27)
				)
			)
		)
		(property "Value" "PM8546A-FEIP-GP"
			(at -25.785064 -6.40334 270)
			(unlocked yes)
			(layer "F.Fab")
			(hide yes)
			(effects
				(font
					(size 1.016 1.016)
					(thickness 0.1524)
				)
			)
		)
		(property "Device Type" "BGA1311C37D5H134"
			(at -25.785064 -7.92734 270)
			(unlocked yes)
			(layer "F.Fab")
			(hide yes)
			(effects
				(font
					(size 1.016 1.016)
					(thickness 0.1524)
				)
			)
		)
		(duplicate_pad_numbers_are_jumpers no)
		(pad "AF32" smd circle
			(at 12.999974 6.999986 270)
			(size 0.4572 0.4572)
			(layers "F.Cu" "F.Mask" "F.Paste")
			(net "RMII_TXD_1")
		)
		(pad "AF33" smd circle
			(at 13.999972 6.999986 270)
			(size 0.4572 0.4572)
			(layers "F.Cu" "F.Mask" "F.Paste")
			(net "RMII_TXD_0")
		)
		(pad "AF34" smd circle
			(at 14.99997 6.999986 270)
			(size 0.4572 0.4572)
			(layers "F.Cu" "F.Mask" "F.Paste")
			(net "GND")
		)
		(pad "AF35" smd circle
			(at 15.999968 6.999986 270)
			(size 0.4572 0.4572)
			(layers "F.Cu" "F.Mask" "F.Paste")
			(net "PCIE_RX_P90")
		)
		(pad "AF36" smd circle
			(at 16.999966 6.999986 270)
			(size 0.4572 0.4572)
			(layers "F.Cu" "F.Mask" "F.Paste")
			(net "PCIE_RX_N90")
		)
		(pad "AG1" smd circle
			(at -17.999964 7.999984 270)
			(size 0.4572 0.4572)
			(layers "F.Cu" "F.Mask" "F.Paste")
			(net "PCIE_TX_CAP_N55")
		)
		(pad "AG2" smd circle
			(at -16.999966 7.999984 270)
			(size 0.4572 0.4572)
			(layers "F.Cu" "F.Mask" "F.Paste")
			(net "PCIE_TX_CAP_P55")
		)
		(pad "AG3" smd circle
			(at -15.999968 7.999984 270)
			(size 0.4572 0.4572)
			(layers "F.Cu" "F.Mask" "F.Paste")
			(net "GND")
		)
		(pad "AG4" smd circle
			(at -14.99997 7.999984 270)
			(size 0.4572 0.4572)
			(layers "F.Cu" "F.Mask" "F.Paste")
			(net "PCIE_RX_N55")
		)
		(pad "AG5" smd circle
			(at -13.999972 7.999984 270)
			(size 0.4572 0.4572)
			(layers "F.Cu" "F.Mask" "F.Paste")
			(net "PCIE_RX_P55")
		)
		(pad "AG6" smd circle
			(at -12.999974 7.999984 270)
			(size 0.4572 0.4572)
			(layers "F.Cu" "F.Mask" "F.Paste")
			(net "GND")
		)
		(pad "AG7" smd circle
			(at -11.999976 7.999984 270)
			(size 0.4572 0.4572)
			(layers "F.Cu" "F.Mask" "F.Paste")
			(net "DUT_AVD_PCIE")
		)
		(pad "AG8" smd circle
			(at -10.999978 7.999984 270)
			(size 0.4572 0.4572)
			(layers "F.Cu" "F.Mask" "F.Paste")
			(net "GND")
		)
		(pad "AG9" smd circle
			(at -9.99998 7.999984 270)
			(size 0.4572 0.4572)
			(layers "F.Cu" "F.Mask" "F.Paste")
			(net "GND")
		)
		(pad "AG10" smd circle
			(at -8.999982 7.999984 270)
			(size 0.4572 0.4572)
			(layers "F.Cu" "F.Mask" "F.Paste")
			(net "GND")
		)
		(pad "AG11" smd circle
			(at -7.999984 7.999984 270)
			(size 0.4572 0.4572)
			(layers "F.Cu" "F.Mask" "F.Paste")
			(net "GND")
		)
		(pad "AG12" smd circle
			(at -6.999986 7.999984 270)
			(size 0.4572 0.4572)
			(layers "F.Cu" "F.Mask" "F.Paste")
			(net "GND")
		)
		(pad "AG13" smd circle
			(at -5.999988 7.999984 270)
			(size 0.4572 0.4572)
			(layers "F.Cu" "F.Mask" "F.Paste")
			(net "DUT_AVD_PCIE_Q")
		)
		(pad "AG14" smd circle
			(at -4.99999 7.999984 270)
			(size 0.4572 0.4572)
			(layers "F.Cu" "F.Mask" "F.Paste")
			(net "GND")
		)
		(pad "AG15" smd circle
			(at -3.999992 7.999984 270)
			(size 0.4572 0.4572)
			(layers "F.Cu" "F.Mask" "F.Paste")
			(net "GND")
		)
		(pad "AG16" smd circle
			(at -2.999994 7.999984 270)
			(size 0.4572 0.4572)
			(layers "F.Cu" "F.Mask" "F.Paste")
			(net "GND")
		)
		(pad "AG17" smd circle
			(at -1.999996 7.999984 270)
			(size 0.4572 0.4572)
			(layers "F.Cu" "F.Mask" "F.Paste")
			(net "GND")
		)
		(pad "AG18" smd circle
			(at -0.999998 7.999984 270)
			(size 0.4572 0.4572)
			(layers "F.Cu" "F.Mask" "F.Paste")
			(net "GND")
		)
		(pad "AG19" smd circle
			(at 0 7.999984 270)
			(size 0.4572 0.4572)
			(layers "F.Cu" "F.Mask" "F.Paste")
			(net "GND")
		)
		(pad "AG20" smd circle
			(at 0.999998 7.999984 270)
			(size 0.4572 0.4572)
			(layers "F.Cu" "F.Mask" "F.Paste")
			(net "DUT_AVD_PCIE_Q")
		)
		(pad "AG21" smd circle
			(at 1.999996 7.999984 270)
			(size 0.4572 0.4572)
			(layers "F.Cu" "F.Mask" "F.Paste")
			(net "GND")
		)
		(pad "AG22" smd circle
			(at 2.999994 7.999984 270)
			(size 0.4572 0.4572)
			(layers "F.Cu" "F.Mask" "F.Paste")
			(net "GND")
		)
		(pad "AG23" smd circle
			(at 3.999992 7.999984 270)
			(size 0.4572 0.4572)
			(layers "F.Cu" "F.Mask" "F.Paste")
			(net "GND")
		)
		(pad "AG24" smd circle
			(at 4.99999 7.999984 270)
			(size 0.4572 0.4572)
			(layers "F.Cu" "F.Mask" "F.Paste")
			(net "GND")
		)
		(pad "AG25" smd circle
			(at 5.999988 7.999984 270)
			(size 0.4572 0.4572)
			(layers "F.Cu" "F.Mask" "F.Paste")
			(net "GND")
		)
		(pad "AG26" smd circle
			(at 6.999986 7.999984 270)
			(size 0.4572 0.4572)
			(layers "F.Cu" "F.Mask" "F.Paste")
			(net "DUT_TDI_R")
		)
		(pad "AG27" smd circle
			(at 7.999984 7.999984 270)
			(size 0.4572 0.4572)
			(layers "F.Cu" "F.Mask" "F.Paste")
			(net "EJTAG_TMS_R")
		)
		(pad "AG28" smd circle
			(at 8.999982 7.999984 270)
			(size 0.4572 0.4572)
			(layers "F.Cu" "F.Mask" "F.Paste")
			(net "EJTAG_TRSTB_R")
		)
		(pad "AG29" smd circle
			(at 9.99998 7.999984 270)
			(size 0.4572 0.4572)
			(layers "F.Cu" "F.Mask" "F.Paste")
			(net "EJTAG_RSTB")
		)
		(pad "AG30" smd circle
			(at 10.999978 7.999984 270)
			(size 0.4572 0.4572)
			(layers "F.Cu" "F.Mask" "F.Paste")
			(net "DUT_TAP_SEL_R")
		)
		(pad "AG31" smd circle
			(at 11.999976 7.999984 270)
			(size 0.4572 0.4572)
			(layers "F.Cu" "F.Mask" "F.Paste")
			(net "DUT_VDDO")
		)
		(pad "AG32" smd circle
			(at 12.999974 7.999984 270)
			(size 0.4572 0.4572)
			(layers "F.Cu" "F.Mask" "F.Paste")
			(net "PM8536_RST#")
		)
		(pad "AG33" smd circle
			(at 13.999972 7.999984 270)
			(size 0.4572 0.4572)
			(layers "F.Cu" "F.Mask" "F.Paste")
			(net "DUT_TDO_R")
		)
		(pad "AG34" smd circle
			(at 14.99997 7.999984 270)
			(size 0.4572 0.4572)
			(layers "F.Cu" "F.Mask" "F.Paste")
			(net "DUT_VDDO")
		)
		(pad "AG35" smd circle
			(at 15.999968 7.999984 270)
			(size 0.4572 0.4572)
			(layers "F.Cu" "F.Mask" "F.Paste")
			(net "GND")
		)
		(pad "AG36" smd circle
			(at 16.999966 7.999984 270)
			(size 0.4572 0.4572)
			(layers "F.Cu" "F.Mask" "F.Paste")
			(net "PCIE_RX_P89")
		)
		(pad "AG37" smd circle
			(at 17.999964 7.999984 270)
			(size 0.4572 0.4572)
			(layers "F.Cu" "F.Mask" "F.Paste")
			(net "PCIE_RX_N89")
		)
		(pad "AH1" smd circle
			(at -17.999964 8.999982 270)
			(size 0.4572 0.4572)
			(layers "F.Cu" "F.Mask" "F.Paste")
			(net "GND")
		)
		(pad "AH2" smd circle
			(at -16.999966 8.999982 270)
			(size 0.4572 0.4572)
			(layers "F.Cu" "F.Mask" "F.Paste")
			(net "GND")
		)
		(pad "AH3" smd circle
			(at -15.999968 8.999982 270)
			(size 0.4572 0.4572)
			(layers "F.Cu" "F.Mask" "F.Paste")
			(net "GND")
		)
		(pad "AH4" smd circle
			(at -14.99997 8.999982 270)
			(size 0.4572 0.4572)
			(layers "F.Cu" "F.Mask" "F.Paste")
			(net "GND")
		)
		(pad "AH5" smd circle
			(at -13.999972 8.999982 270)
			(size 0.4572 0.4572)
			(layers "F.Cu" "F.Mask" "F.Paste")
			(net "GND")
		)
		(pad "AH6" smd circle
			(at -12.999974 8.999982 270)
			(size 0.4572 0.4572)
			(layers "F.Cu" "F.Mask" "F.Paste")
			(net "GND")
		)
		(pad "AH7" smd circle
			(at -11.999976 8.999982 270)
			(size 0.4572 0.4572)
			(layers "F.Cu" "F.Mask" "F.Paste")
			(net "DUT_AVD_PCIE")
		)
		(pad "AH8" smd circle
			(at -10.999978 8.999982 270)
			(size 0.4572 0.4572)
			(layers "F.Cu" "F.Mask" "F.Paste")
			(net "GND")
		)
		(pad "AH9" smd circle
			(at -9.99998 8.999982 270)
			(size 0.4572 0.4572)
			(layers "F.Cu" "F.Mask" "F.Paste")
			(net "GND")
		)
		(pad "AH10" smd circle
			(at -8.999982 8.999982 270)
			(size 0.4572 0.4572)
			(layers "F.Cu" "F.Mask" "F.Paste")
			(net "GND")
		)
		(pad "AH11" smd circle
			(at -7.999984 8.999982 270)
			(size 0.4572 0.4572)
			(layers "F.Cu" "F.Mask" "F.Paste")
			(net "GND")
		)
		(pad "AH12" smd circle
			(at -6.999986 8.999982 270)
			(size 0.4572 0.4572)
			(layers "F.Cu" "F.Mask" "F.Paste")
			(net "GND")
		)
		(pad "AH13" smd circle
			(at -5.999988 8.999982 270)
			(size 0.4572 0.4572)
			(layers "F.Cu" "F.Mask" "F.Paste")
			(net "GND")
		)
		(pad "AH14" smd circle
			(at -4.99999 8.999982 270)
			(size 0.4572 0.4572)
			(layers "F.Cu" "F.Mask" "F.Paste")
			(net "GND")
		)
		(pad "AH15" smd circle
			(at -3.999992 8.999982 270)
			(size 0.4572 0.4572)
			(layers "F.Cu" "F.Mask" "F.Paste")
			(net "GND")
		)
		(pad "AH16" smd circle
			(at -2.999994 8.999982 270)
			(size 0.4572 0.4572)
			(layers "F.Cu" "F.Mask" "F.Paste")
			(net "GND")
		)
		(pad "AH17" smd circle
			(at -1.999996 8.999982 270)
			(size 0.4572 0.4572)
			(layers "F.Cu" "F.Mask" "F.Paste")
			(net "GND")
		)
		(pad "AH18" smd circle
			(at -0.999998 8.999982 270)
			(size 0.4572 0.4572)
			(layers "F.Cu" "F.Mask" "F.Paste")
			(net "GND")
		)
		(pad "AH19" smd circle
			(at 0 8.999982 270)
			(size 0.4572 0.4572)
			(layers "F.Cu" "F.Mask" "F.Paste")
			(net "GND")
		)
		(pad "AH20" smd circle
			(at 0.999998 8.999982 270)
			(size 0.4572 0.4572)
			(layers "F.Cu" "F.Mask" "F.Paste")
			(net "GND")
		)
		(pad "AH21" smd circle
			(at 1.999996 8.999982 270)
			(size 0.4572 0.4572)
			(layers "F.Cu" "F.Mask" "F.Paste")
			(net "GND")
		)
		(pad "AH22" smd circle
			(at 2.999994 8.999982 270)
			(size 0.4572 0.4572)
			(layers "F.Cu" "F.Mask" "F.Paste")
			(net "GND")
		)
		(pad "AH23" smd circle
			(at 3.999992 8.999982 270)
			(size 0.4572 0.4572)
			(layers "F.Cu" "F.Mask" "F.Paste")
			(net "GND")
		)
		(pad "AH24" smd circle
			(at 4.99999 8.999982 270)
			(size 0.4572 0.4572)
			(layers "F.Cu" "F.Mask" "F.Paste")
			(net "GND")
		)
		(pad "AH25" smd circle
			(at 5.999988 8.999982 270)
			(size 0.4572 0.4572)
			(layers "F.Cu" "F.Mask" "F.Paste")
			(net "GND")
		)
		(pad "AH26" smd circle
			(at 6.999986 8.999982 270)
			(size 0.4572 0.4572)
			(layers "F.Cu" "F.Mask" "F.Paste")
			(net "LINK")
		)
		(pad "AH27" smd circle
			(at 7.999984 8.999982 270)
			(size 0.4572 0.4572)
			(layers "F.Cu" "F.Mask" "F.Paste")
			(net "MDIO")
		)
		(pad "AH28" smd circle
			(at 8.999982 8.999982 270)
			(size 0.4572 0.4572)
			(layers "F.Cu" "F.Mask" "F.Paste")
			(net "Net_2106")
		)
		(pad "AH29" smd circle
			(at 9.99998 8.999982 270)
			(size 0.4572 0.4572)
			(layers "F.Cu" "F.Mask" "F.Paste")
			(net "GND")
		)
		(pad "AH30" smd circle
			(at 10.999978 8.999982 270)
			(size 0.4572 0.4572)
			(layers "F.Cu" "F.Mask" "F.Paste")
			(net "MDC")
		)
		(pad "AH31" smd circle
			(at 11.999976 8.999982 270)
			(size 0.4572 0.4572)
			(layers "F.Cu" "F.Mask" "F.Paste")
			(net "VSS_571")
		)
		(pad "AH32" smd circle
			(at 12.999974 8.999982 270)
			(size 0.4572 0.4572)
			(layers "F.Cu" "F.Mask" "F.Paste")
			(net "GND")
		)
		(pad "AH33" smd circle
			(at 13.999972 8.999982 270)
			(size 0.4572 0.4572)
			(layers "F.Cu" "F.Mask" "F.Paste")
			(net "BOOT_RECOVERY#")
		)
		(pad "AH34" smd circle
			(at 14.99997 8.999982 270)
			(size 0.4572 0.4572)
			(layers "F.Cu" "F.Mask" "F.Paste")
			(net "GND")
		)
		(pad "AH35" smd circle
			(at 15.999968 8.999982 270)
			(size 0.4572 0.4572)
			(layers "F.Cu" "F.Mask" "F.Paste")
			(net "PCIE_RX_P88")
		)
		(pad "AH36" smd circle
			(at 16.999966 8.999982 270)
			(size 0.4572 0.4572)
			(layers "F.Cu" "F.Mask" "F.Paste")
			(net "PCIE_RX_N88")
		)
		(pad "AJ2" smd circle
			(at -16.999966 9.99998 270)
			(size 0.4572 0.4572)
			(layers "F.Cu" "F.Mask" "F.Paste")
			(net "PCIE_TX_CAP_N56")
		)
		(pad "AJ3" smd circle
			(at -15.999968 9.99998 270)
			(size 0.4572 0.4572)
			(layers "F.Cu" "F.Mask" "F.Paste")
			(net "PCIE_TX_CAP_P56")
		)
		(pad "AJ4" smd circle
			(at -14.99997 9.99998 270)
			(size 0.4572 0.4572)
			(layers "F.Cu" "F.Mask" "F.Paste")
			(net "GND")
		)
		(pad "AJ5" smd circle
			(at -13.999972 9.99998 270)
			(size 0.4572 0.4572)
			(layers "F.Cu" "F.Mask" "F.Paste")
			(net "PCIE_RX_N56")
		)
		(pad "AJ6" smd circle
			(at -12.999974 9.99998 270)
			(size 0.4572 0.4572)
			(layers "F.Cu" "F.Mask" "F.Paste")
			(net "PCIE_RX_P56")
		)
		(pad "AJ7" smd circle
			(at -11.999976 9.99998 270)
			(size 0.4572 0.4572)
			(layers "F.Cu" "F.Mask" "F.Paste")
			(net "DUT_AVD_PCIE")
		)
		(pad "AJ8" smd circle
			(at -10.999978 9.99998 270)
			(size 0.4572 0.4572)
			(layers "F.Cu" "F.Mask" "F.Paste")
			(net "GND")
		)
		(pad "AJ9" smd circle
			(at -9.99998 9.99998 270)
			(size 0.4572 0.4572)
			(layers "F.Cu" "F.Mask" "F.Paste")
			(net "GND")
		)
		(pad "AJ10" smd circle
			(at -8.999982 9.99998 270)
			(size 0.4572 0.4572)
			(layers "F.Cu" "F.Mask" "F.Paste")
			(net "GND")
		)
		(pad "AJ11" smd circle
			(at -7.999984 9.99998 270)
			(size 0.4572 0.4572)
			(layers "F.Cu" "F.Mask" "F.Paste")
			(net "GND")
		)
		(pad "AJ12" smd circle
			(at -6.999986 9.99998 270)
			(size 0.4572 0.4572)
			(layers "F.Cu" "F.Mask" "F.Paste")
			(net "GND")
		)
		(pad "AJ13" smd circle
			(at -5.999988 9.99998 270)
			(size 0.4572 0.4572)
			(layers "F.Cu" "F.Mask" "F.Paste")
			(net "GND")
		)
		(pad "AJ14" smd circle
			(at -4.99999 9.99998 270)
			(size 0.4572 0.4572)
			(layers "F.Cu" "F.Mask" "F.Paste")
			(net "GND")
		)
		(pad "AJ15" smd circle
			(at -3.999992 9.99998 270)
			(size 0.4572 0.4572)
			(layers "F.Cu" "F.Mask" "F.Paste")
			(net "GND")
		)
		(pad "AJ16" smd circle
			(at -2.999994 9.99998 270)
			(size 0.4572 0.4572)
			(layers "F.Cu" "F.Mask" "F.Paste")
			(net "GND")
		)
		(pad "AJ17" smd circle
			(at -1.999996 9.99998 270)
			(size 0.4572 0.4572)
			(layers "F.Cu" "F.Mask" "F.Paste")
			(net "GND")
		)
		(pad "AJ18" smd circle
			(at -0.999998 9.99998 270)
			(size 0.4572 0.4572)
			(layers "F.Cu" "F.Mask" "F.Paste")
			(net "GND")
		)
		(pad "AJ19" smd circle
			(at 0 9.99998 270)
			(size 0.4572 0.4572)
			(layers "F.Cu" "F.Mask" "F.Paste")
			(net "GND")
		)
		(pad "AJ20" smd circle
			(at 0.999998 9.99998 270)
			(size 0.4572 0.4572)
			(layers "F.Cu" "F.Mask" "F.Paste")
			(net "DUT_AVD_PCIE")
		)
		(pad "AJ21" smd circle
			(at 1.999996 9.99998 270)
			(size 0.4572 0.4572)
			(layers "F.Cu" "F.Mask" "F.Paste")
			(net "GND")
		)
		(pad "AJ22" smd circle
			(at 2.999994 9.99998 270)
			(size 0.4572 0.4572)
			(layers "F.Cu" "F.Mask" "F.Paste")
			(net "GND")
		)
		(pad "AJ23" smd circle
			(at 3.999992 9.99998 270)
			(size 0.4572 0.4572)
			(layers "F.Cu" "F.Mask" "F.Paste")
			(net "GND")
		)
		(pad "AJ24" smd circle
			(at 4.99999 9.99998 270)
			(size 0.4572 0.4572)
			(layers "F.Cu" "F.Mask" "F.Paste")
			(net "GND")
		)
		(pad "AJ25" smd circle
			(at 5.999988 9.99998 270)
			(size 0.4572 0.4572)
			(layers "F.Cu" "F.Mask" "F.Paste")
			(net "DUT_AVD_PCIE")
		)
		(pad "AJ26" smd circle
			(at 6.999986 9.99998 270)
			(size 0.4572 0.4572)
			(layers "F.Cu" "F.Mask" "F.Paste")
			(net "GND")
		)
		(pad "AJ27" smd circle
			(at 7.999984 9.99998 270)
			(size 0.4572 0.4572)
			(layers "F.Cu" "F.Mask" "F.Paste")
			(net "SPI_CSB0_0")
		)
		(pad "AJ28" smd circle
			(at 8.999982 9.99998 270)
			(size 0.4572 0.4572)
			(layers "F.Cu" "F.Mask" "F.Paste")
			(net "SPI_CSB0_1")
		)
		(pad "AJ29" smd circle
			(at 9.99998 9.99998 270)
			(size 0.4572 0.4572)
			(layers "F.Cu" "F.Mask" "F.Paste")
			(net "SPI_DATA0_0")
		)
		(pad "AJ30" smd circle
			(at 10.999978 9.99998 270)
			(size 0.4572 0.4572)
			(layers "F.Cu" "F.Mask" "F.Paste")
			(net "SPI_DATA0_1")
		)
		(pad "AJ31" smd circle
			(at 11.999976 9.99998 270)
			(size 0.4572 0.4572)
			(layers "F.Cu" "F.Mask" "F.Paste")
			(net "SPI_CLK0")
		)
		(pad "AJ32" smd circle
			(at 12.999974 9.99998 270)
			(size 0.4572 0.4572)
			(layers "F.Cu" "F.Mask" "F.Paste")
			(net "SPI_DATA0_2")
		)
		(pad "AJ33" smd circle
			(at 13.999972 9.99998 270)
			(size 0.4572 0.4572)
			(layers "F.Cu" "F.Mask" "F.Paste")
			(net "SPI_DATA0_3")
		)
		(pad "AJ34" smd circle
			(at 14.99997 9.99998 270)
			(size 0.4572 0.4572)
			(layers "F.Cu" "F.Mask" "F.Paste")
			(net "DUT_VDDO")
		)
		(pad "AJ35" smd circle
			(at 15.999968 9.99998 270)
			(size 0.4572 0.4572)
			(layers "F.Cu" "F.Mask" "F.Paste")
			(net "GND")
		)
		(pad "AJ36" smd circle
			(at 16.999966 9.99998 270)
			(size 0.4572 0.4572)
			(layers "F.Cu" "F.Mask" "F.Paste")
			(net "GND")
		)
		(pad "AJ37" smd circle
			(at 17.999964 9.99998 270)
			(size 0.4572 0.4572)
			(layers "F.Cu" "F.Mask" "F.Paste")
			(net "GND")
		)
		(pad "AK1" smd circle
			(at -17.999964 10.999978 270)
			(size 0.4572 0.4572)
			(layers "F.Cu" "F.Mask" "F.Paste")
			(net "PCIE_TX_CAP_N57")
		)
		(pad "AK2" smd circle
			(at -16.999966 10.999978 270)
			(size 0.4572 0.4572)
			(layers "F.Cu" "F.Mask" "F.Paste")
			(net "PCIE_TX_CAP_P57")
		)
		(pad "AK3" smd circle
			(at -15.999968 10.999978 270)
			(size 0.4572 0.4572)
			(layers "F.Cu" "F.Mask" "F.Paste")
			(net "GND")
		)
		(pad "AK4" smd circle
			(at -14.99997 10.999978 270)
			(size 0.4572 0.4572)
			(layers "F.Cu" "F.Mask" "F.Paste")
			(net "PCIE_RX_N57")
		)
		(pad "AK5" smd circle
			(at -13.999972 10.999978 270)
			(size 0.4572 0.4572)
			(layers "F.Cu" "F.Mask" "F.Paste")
			(net "PCIE_RX_P57")
		)
	)
)
